(kicad_pcb
	(version 20260206)
	(generator "pcbnew")
	(generator_version "10.0")
	(general
		(thickness 1.6)
		(legacy_teardrops no)
	)
	(paper "A4")
	(title_block
		(title "04192023_DAF0TMB3IC0_F0TG_MB_C_brd_V02_OCP.brd")
		(comment 1 "Grand Teton / footprints 3628-3634 of 8354")
	)
	(layers
		(0 "F.Cu" signal "TOP")
		(4 "In1.Cu" signal "GND")
		(6 "In2.Cu" signal "IN1")
		(8 "In3.Cu" signal "GND1")
		(10 "In4.Cu" signal "IN2")
		(12 "In5.Cu" signal "GND2")
		(14 "In6.Cu" signal "IN3")
		(16 "In7.Cu" signal "GND3")
		(18 "In8.Cu" signal "VCC")
		(20 "In9.Cu" signal "VCC1")
		(22 "In10.Cu" signal "GND4")
		(24 "In11.Cu" signal "IN4")
		(26 "In12.Cu" signal "GND5")
		(28 "In13.Cu" signal "IN5")
		(30 "In14.Cu" signal "GND6")
		(32 "In15.Cu" signal "IN6")
		(34 "In16.Cu" signal "GND7")
		(2 "B.Cu" signal "BOTTOM")
		(9 "F.Adhes" user "F.Adhesive")
		(11 "B.Adhes" user "B.Adhesive")
		(13 "F.Paste" user "Package Geometry/Pastemask Top")
		(15 "B.Paste" user "Package Geometry/Pastemask Bottom")
		(5 "F.SilkS" user "Ref Des/Silkscreen Top")
		(7 "B.SilkS" user "Ref Des/Silkscreen Bottom")
		(1 "F.Mask" user "Board Geometry/Soldermask Top")
		(3 "B.Mask" user "Board Geometry/Soldermask Bottom")
		(17 "Dwgs.User" user "User.Drawings")
		(19 "Cmts.User" user "User.Comments")
		(21 "Eco1.User" user "User.Eco1")
		(23 "Eco2.User" user "User.Eco2")
		(25 "Edge.Cuts" user "Board Geometry/Outline")
		(27 "Margin" user)
		(31 "F.CrtYd" user "Package Geometry/Place Bound Top")
		(29 "B.CrtYd" user "Package Geometry/Place Bound Bottom")
		(35 "F.Fab" user "Ref Des/Assembly Top")
		(33 "B.Fab" user "Ref Des/Assembly Bottom")
	)
	(footprint ""
		(layer "F.Cu")
		(at 120.396 -434.467 180)
		(property "Reference" "R3494"
			(at 0 0 180)
			(layer "F.SilkS")
			(hide yes)
			(effects
				(font
					(size 1.27 1.27)
				)
			)
		)
		(property "Value" ""
			(at 0 0 180)
			(layer "F.Fab")
			(effects
				(font
					(size 1.27 1.27)
				)
			)
		)
		(duplicate_pad_numbers_are_jumpers no)
		(fp_line
			(start 0.7874 0.4064)
			(end -0.7874 0.4064)
			(stroke
				(width 0.1524)
				(type default)
			)
			(layer "F.SilkS")
		)
		(fp_line
			(start 0.7874 -0.4064)
			(end 0.7874 0.4064)
			(stroke
				(width 0.1524)
				(type default)
			)
			(layer "F.SilkS")
		)
		(fp_line
			(start -0.7874 0.4064)
			(end -0.7874 -0.4064)
			(stroke
				(width 0.1524)
				(type default)
			)
			(layer "F.SilkS")
		)
		(fp_line
			(start -0.7874 -0.4064)
			(end 0.7874 -0.4064)
			(stroke
				(width 0.1524)
				(type default)
			)
			(layer "F.SilkS")
		)
		(fp_line
			(start 0.67945 0.3048)
			(end 0.120396 0.3048)
			(stroke
				(width 0.1)
				(type default)
			)
			(layer "F.Fab")
		)
		(fp_line
			(start 0.67945 -0.3048)
			(end 0.67945 0.3048)
			(stroke
				(width 0.1)
				(type default)
			)
			(layer "F.Fab")
		)
		(fp_line
			(start 0.12065 -0.2794)
			(end 0.12065 -0.3048)
			(stroke
				(width 0.1)
				(type default)
			)
			(layer "F.Fab")
		)
		(fp_line
			(start 0.12065 -0.3048)
			(end 0.67945 -0.3048)
			(stroke
				(width 0.1)
				(type default)
			)
			(layer "F.Fab")
		)
		(fp_line
			(start 0.120396 0.3048)
			(end 0.120396 0.2794)
			(stroke
				(width 0.1)
				(type default)
			)
			(layer "F.Fab")
		)
		(fp_line
			(start 0.120396 0.2794)
			(end -0.12065 0.2794)
			(stroke
				(width 0.1)
				(type default)
			)
			(layer "F.Fab")
		)
		(fp_line
			(start -0.12065 0.3048)
			(end -0.67945 0.3048)
			(stroke
				(width 0.1)
				(type default)
			)
			(layer "F.Fab")
		)
		(fp_line
			(start -0.12065 0.2794)
			(end -0.12065 0.3048)
			(stroke
				(width 0.1)
				(type default)
			)
			(layer "F.Fab")
		)
		(fp_line
			(start -0.12065 -0.2794)
			(end 0.12065 -0.2794)
			(stroke
				(width 0.1)
				(type default)
			)
			(layer "F.Fab")
		)
		(fp_line
			(start -0.12065 -0.305054)
			(end -0.12065 -0.2794)
			(stroke
				(width 0.1)
				(type default)
			)
			(layer "F.Fab")
		)
		(fp_line
			(start -0.67945 0.3048)
			(end -0.67945 -0.305054)
			(stroke
				(width 0.1)
				(type default)
			)
			(layer "F.Fab")
		)
		(fp_line
			(start -0.67945 -0.305054)
			(end -0.12065 -0.305054)
			(stroke
				(width 0.1)
				(type default)
			)
			(layer "F.Fab")
		)
		(pad "1" smd circle
			(at -0.40005 0 180)
			(size 0 0)
			(layers "F.Cu" "F.Mask" "F.Paste")
			(net "P3V3_AUX")
		)
		(pad "2" smd circle
			(at 0.40005 0 180)
			(size 0 0)
			(layers "F.Cu" "F.Mask" "F.Paste")
			(net "GPU_FPGA_EROT_RECOV_BUF_R_N")
		)
	)
	(footprint ""
		(layer "F.Cu")
		(at 452.13905 -48.462946)
		(property "Reference" "R1571"
			(at 0 0 0)
			(layer "F.SilkS")
			(hide yes)
			(effects
				(font
					(size 1.27 1.27)
				)
			)
		)
		(property "Value" ""
			(at 0 0 0)
			(layer "F.Fab")
			(effects
				(font
					(size 1.27 1.27)
				)
			)
		)
		(duplicate_pad_numbers_are_jumpers no)
		(fp_line
			(start -0.7874 -0.4064)
			(end 0.7874 -0.4064)
			(stroke
				(width 0.1524)
				(type default)
			)
			(layer "F.SilkS")
		)
		(fp_line
			(start -0.7874 0.4064)
			(end -0.7874 -0.4064)
			(stroke
				(width 0.1524)
				(type default)
			)
			(layer "F.SilkS")
		)
		(fp_line
			(start 0.7874 -0.4064)
			(end 0.7874 0.4064)
			(stroke
				(width 0.1524)
				(type default)
			)
			(layer "F.SilkS")
		)
		(fp_line
			(start 0.7874 0.4064)
			(end -0.7874 0.4064)
			(stroke
				(width 0.1524)
				(type default)
			)
			(layer "F.SilkS")
		)
		(fp_line
			(start -0.67945 -0.305054)
			(end -0.12065 -0.305054)
			(stroke
				(width 0.1)
				(type default)
			)
			(layer "F.Fab")
		)
		(fp_line
			(start -0.67945 0.3048)
			(end -0.67945 -0.305054)
			(stroke
				(width 0.1)
				(type default)
			)
			(layer "F.Fab")
		)
		(fp_line
			(start -0.12065 -0.305054)
			(end -0.12065 -0.2794)
			(stroke
				(width 0.1)
				(type default)
			)
			(layer "F.Fab")
		)
		(fp_line
			(start -0.12065 -0.2794)
			(end 0.12065 -0.2794)
			(stroke
				(width 0.1)
				(type default)
			)
			(layer "F.Fab")
		)
		(fp_line
			(start -0.12065 0.2794)
			(end -0.12065 0.3048)
			(stroke
				(width 0.1)
				(type default)
			)
			(layer "F.Fab")
		)
		(fp_line
			(start -0.12065 0.3048)
			(end -0.67945 0.3048)
			(stroke
				(width 0.1)
				(type default)
			)
			(layer "F.Fab")
		)
		(fp_line
			(start 0.120396 0.2794)
			(end -0.12065 0.2794)
			(stroke
				(width 0.1)
				(type default)
			)
			(layer "F.Fab")
		)
		(fp_line
			(start 0.120396 0.3048)
			(end 0.120396 0.2794)
			(stroke
				(width 0.1)
				(type default)
			)
			(layer "F.Fab")
		)
		(fp_line
			(start 0.12065 -0.3048)
			(end 0.67945 -0.3048)
			(stroke
				(width 0.1)
				(type default)
			)
			(layer "F.Fab")
		)
		(fp_line
			(start 0.12065 -0.2794)
			(end 0.12065 -0.3048)
			(stroke
				(width 0.1)
				(type default)
			)
			(layer "F.Fab")
		)
		(fp_line
			(start 0.67945 -0.3048)
			(end 0.67945 0.3048)
			(stroke
				(width 0.1)
				(type default)
			)
			(layer "F.Fab")
		)
		(fp_line
			(start 0.67945 0.3048)
			(end 0.120396 0.3048)
			(stroke
				(width 0.1)
				(type default)
			)
			(layer "F.Fab")
		)
		(pad "1" smd circle
			(at -0.40005 0)
			(size 0 0)
			(layers "F.Cu" "F.Mask" "F.Paste")
			(net "PWRGD_P5V_AUX")
		)
		(pad "2" smd circle
			(at 0.40005 0)
			(size 0 0)
			(layers "F.Cu" "F.Mask" "F.Paste")
			(net "P3V3_AUX_EN")
		)
	)
	(footprint ""
		(layer "F.Cu")
		(at 277.650956 -429.572166 180)
		(property "Reference" "R4265"
			(at 0 0 180)
			(layer "F.SilkS")
			(hide yes)
			(effects
				(font
					(size 1.27 1.27)
				)
			)
		)
		(property "Value" ""
			(at 0 0 180)
			(layer "F.Fab")
			(effects
				(font
					(size 1.27 1.27)
				)
			)
		)
		(duplicate_pad_numbers_are_jumpers no)
		(fp_line
			(start 0.7874 0.4064)
			(end -0.7874 0.4064)
			(stroke
				(width 0.1524)
				(type default)
			)
			(layer "F.SilkS")
		)
		(fp_line
			(start 0.7874 -0.4064)
			(end 0.7874 0.4064)
			(stroke
				(width 0.1524)
				(type default)
			)
			(layer "F.SilkS")
		)
		(fp_line
			(start -0.7874 0.4064)
			(end -0.7874 -0.4064)
			(stroke
				(width 0.1524)
				(type default)
			)
			(layer "F.SilkS")
		)
		(fp_line
			(start -0.7874 -0.4064)
			(end 0.7874 -0.4064)
			(stroke
				(width 0.1524)
				(type default)
			)
			(layer "F.SilkS")
		)
		(fp_line
			(start 0.67945 0.3048)
			(end 0.120396 0.3048)
			(stroke
				(width 0.1)
				(type default)
			)
			(layer "F.Fab")
		)
		(fp_line
			(start 0.67945 -0.3048)
			(end 0.67945 0.3048)
			(stroke
				(width 0.1)
				(type default)
			)
			(layer "F.Fab")
		)
		(fp_line
			(start 0.12065 -0.2794)
			(end 0.12065 -0.3048)
			(stroke
				(width 0.1)
				(type default)
			)
			(layer "F.Fab")
		)
		(fp_line
			(start 0.12065 -0.3048)
			(end 0.67945 -0.3048)
			(stroke
				(width 0.1)
				(type default)
			)
			(layer "F.Fab")
		)
		(fp_line
			(start 0.120396 0.3048)
			(end 0.120396 0.2794)
			(stroke
				(width 0.1)
				(type default)
			)
			(layer "F.Fab")
		)
		(fp_line
			(start 0.120396 0.2794)
			(end -0.12065 0.2794)
			(stroke
				(width 0.1)
				(type default)
			)
			(layer "F.Fab")
		)
		(fp_line
			(start -0.12065 0.3048)
			(end -0.67945 0.3048)
			(stroke
				(width 0.1)
				(type default)
			)
			(layer "F.Fab")
		)
		(fp_line
			(start -0.12065 0.2794)
			(end -0.12065 0.3048)
			(stroke
				(width 0.1)
				(type default)
			)
			(layer "F.Fab")
		)
		(fp_line
			(start -0.12065 -0.2794)
			(end 0.12065 -0.2794)
			(stroke
				(width 0.1)
				(type default)
			)
			(layer "F.Fab")
		)
		(fp_line
			(start -0.12065 -0.305054)
			(end -0.12065 -0.2794)
			(stroke
				(width 0.1)
				(type default)
			)
			(layer "F.Fab")
		)
		(fp_line
			(start -0.67945 0.3048)
			(end -0.67945 -0.305054)
			(stroke
				(width 0.1)
				(type default)
			)
			(layer "F.Fab")
		)
		(fp_line
			(start -0.67945 -0.305054)
			(end -0.12065 -0.305054)
			(stroke
				(width 0.1)
				(type default)
			)
			(layer "F.Fab")
		)
		(pad "1" smd circle
			(at -0.40005 0 180)
			(size 0 0)
			(layers "F.Cu" "F.Mask" "F.Paste")
			(net "PWRGD_P3V3_AUX_PDB_BUF_R")
		)
		(pad "2" smd circle
			(at 0.40005 0 180)
			(size 0 0)
			(layers "F.Cu" "F.Mask" "F.Paste")
			(net "GND")
		)
	)
	(footprint ""
		(layer "F.Cu")
		(at 418.896038 -353.763072 90)
		(property "Reference" "PR411"
			(at 0 0 90)
			(layer "F.SilkS")
			(hide yes)
			(effects
				(font
					(size 1.27 1.27)
				)
			)
		)
		(property "Value" ""
			(at 0 0 90)
			(layer "F.Fab")
			(effects
				(font
					(size 1.27 1.27)
				)
			)
		)
		(duplicate_pad_numbers_are_jumpers no)
		(fp_line
			(start 0.7874 -0.4064)
			(end 0.7874 0.4064)
			(stroke
				(width 0.1524)
				(type default)
			)
			(layer "F.SilkS")
		)
		(fp_line
			(start -0.7874 -0.4064)
			(end 0.7874 -0.4064)
			(stroke
				(width 0.1524)
				(type default)
			)
			(layer "F.SilkS")
		)
		(fp_line
			(start 0.7874 0.4064)
			(end -0.7874 0.4064)
			(stroke
				(width 0.1524)
				(type default)
			)
			(layer "F.SilkS")
		)
		(fp_line
			(start -0.7874 0.4064)
			(end -0.7874 -0.4064)
			(stroke
				(width 0.1524)
				(type default)
			)
			(layer "F.SilkS")
		)
		(fp_line
			(start -0.12065 -0.305054)
			(end -0.12065 -0.2794)
			(stroke
				(width 0.1)
				(type default)
			)
			(layer "F.Fab")
		)
		(fp_line
			(start -0.67945 -0.305054)
			(end -0.12065 -0.305054)
			(stroke
				(width 0.1)
				(type default)
			)
			(layer "F.Fab")
		)
		(fp_line
			(start 0.67945 -0.3048)
			(end 0.67945 0.3048)
			(stroke
				(width 0.1)
				(type default)
			)
			(layer "F.Fab")
		)
		(fp_line
			(start 0.12065 -0.3048)
			(end 0.67945 -0.3048)
			(stroke
				(width 0.1)
				(type default)
			)
			(layer "F.Fab")
		)
		(fp_line
			(start 0.12065 -0.2794)
			(end 0.12065 -0.3048)
			(stroke
				(width 0.1)
				(type default)
			)
			(layer "F.Fab")
		)
		(fp_line
			(start -0.12065 -0.2794)
			(end 0.12065 -0.2794)
			(stroke
				(width 0.1)
				(type default)
			)
			(layer "F.Fab")
		)
		(fp_line
			(start 0.120396 0.2794)
			(end -0.12065 0.2794)
			(stroke
				(width 0.1)
				(type default)
			)
			(layer "F.Fab")
		)
		(fp_line
			(start -0.12065 0.2794)
			(end -0.12065 0.3048)
			(stroke
				(width 0.1)
				(type default)
			)
			(layer "F.Fab")
		)
		(fp_line
			(start 0.67945 0.3048)
			(end 0.120396 0.3048)
			(stroke
				(width 0.1)
				(type default)
			)
			(layer "F.Fab")
		)
		(fp_line
			(start 0.120396 0.3048)
			(end 0.120396 0.2794)
			(stroke
				(width 0.1)
				(type default)
			)
			(layer "F.Fab")
		)
		(fp_line
			(start -0.12065 0.3048)
			(end -0.67945 0.3048)
			(stroke
				(width 0.1)
				(type default)
			)
			(layer "F.Fab")
		)
		(fp_line
			(start -0.67945 0.3048)
			(end -0.67945 -0.305054)
			(stroke
				(width 0.1)
				(type default)
			)
			(layer "F.Fab")
		)
		(pad "1" smd circle
			(at -0.40005 0 90)
			(size 0 0)
			(layers "F.Cu" "F.Mask" "F.Paste")
			(net "PVDD11_S3_P0_PVCC")
		)
		(pad "2" smd circle
			(at 0.40005 0 90)
			(size 0 0)
			(layers "F.Cu" "F.Mask" "F.Paste")
			(net "P5V_AUX")
		)
	)
	(footprint ""
		(layer "F.Cu")
		(at 240.792 -287.0708 180)
		(property "Reference" "PC6902"
			(at 0 0 180)
			(layer "F.SilkS")
			(hide yes)
			(effects
				(font
					(size 1.27 1.27)
				)
			)
		)
		(property "Value" ""
			(at 0 0 180)
			(layer "F.Fab")
			(effects
				(font
					(size 1.27 1.27)
				)
			)
		)
		(duplicate_pad_numbers_are_jumpers no)
		(fp_line
			(start 1.524 0.762)
			(end -1.524 0.762)
			(stroke
				(width 0.1524)
				(type default)
			)
			(layer "F.SilkS")
		)
		(fp_line
			(start 1.524 -0.762)
			(end 1.524 0.762)
			(stroke
				(width 0.1524)
				(type default)
			)
			(layer "F.SilkS")
		)
		(fp_line
			(start -1.524 0.762)
			(end -1.524 -0.762)
			(stroke
				(width 0.1524)
				(type default)
			)
			(layer "F.SilkS")
		)
		(fp_line
			(start -1.524 -0.762)
			(end 1.524 -0.762)
			(stroke
				(width 0.1524)
				(type default)
			)
			(layer "F.SilkS")
		)
		(fp_line
			(start 1.1049 0.724916)
			(end 1.1049 -0.724916)
			(stroke
				(width 0.1)
				(type default)
			)
			(layer "F.Fab")
		)
		(fp_line
			(start 1.1049 -0.724916)
			(end -1.1049 -0.724916)
			(stroke
				(width 0.1)
				(type default)
			)
			(layer "F.Fab")
		)
		(fp_line
			(start -1.1049 0.724916)
			(end 1.1049 0.724916)
			(stroke
				(width 0.1)
				(type default)
			)
			(layer "F.Fab")
		)
		(fp_line
			(start -1.1049 -0.724916)
			(end -1.1049 0.724916)
			(stroke
				(width 0.1)
				(type default)
			)
			(layer "F.Fab")
		)
		(pad "1" smd rect
			(at -0.889 0)
			(size 1.016 1.27)
			(layers "F.Cu" "F.Mask" "F.Paste")
			(net "SW_P12V_AUX_P1V8_RETIMER_CPU0_FLT")
		)
		(pad "2" smd rect
			(at 0.889 0)
			(size 1.016 1.27)
			(layers "F.Cu" "F.Mask" "F.Paste")
			(net "GND")
		)
	)
	(footprint ""
		(layer "F.Cu")
		(at 392.311382 -416.899344 -90)
		(property "Reference" "C6580"
			(at 0 0 270)
			(layer "F.SilkS")
			(hide yes)
			(effects
				(font
					(size 1.27 1.27)
				)
			)
		)
		(property "Value" ""
			(at 0 0 270)
			(layer "F.Fab")
			(effects
				(font
					(size 1.27 1.27)
				)
			)
		)
		(duplicate_pad_numbers_are_jumpers no)
		(fp_line
			(start -0.299974 0.150114)
			(end -0.299974 -0.150114)
			(stroke
				(width 0.1)
				(type default)
			)
			(layer "F.Fab")
		)
		(fp_line
			(start 0.299974 0.150114)
			(end -0.299974 0.150114)
			(stroke
				(width 0.1)
				(type default)
			)
			(layer "F.Fab")
		)
		(fp_line
			(start -0.299974 -0.150114)
			(end 0.299974 -0.150114)
			(stroke
				(width 0.1)
				(type default)
			)
			(layer "F.Fab")
		)
		(fp_line
			(start 0.299974 -0.150114)
			(end 0.299974 0.150114)
			(stroke
				(width 0.1)
				(type default)
			)
			(layer "F.Fab")
		)
		(pad "1" smd rect
			(at -0.2667 0 270)
			(size 0.3048 0.381)
			(layers "F.Cu" "F.Mask" "F.Paste")
			(net "P5E_CPU0_P2_TX_BUF_C_DN<7>")
		)
		(pad "2" smd rect
			(at 0.2667 0 270)
			(size 0.3048 0.381)
			(layers "F.Cu" "F.Mask" "F.Paste")
			(net "P5E_CPU0_P2_TX_BUF_DN<7>")
		)
	)
	(footprint ""
		(layer "F.Cu")
		(at 58.297064 -39.003986 90)
		(property "Reference" "R1182"
			(at 0 0 90)
			(layer "F.SilkS")
			(hide yes)
			(effects
				(font
					(size 1.27 1.27)
				)
			)
		)
		(property "Value" ""
			(at 0 0 90)
			(layer "F.Fab")
			(effects
				(font
					(size 1.27 1.27)
				)
			)
		)
		(duplicate_pad_numbers_are_jumpers no)
		(fp_line
			(start 0.7874 -0.4064)
			(end 0.7874 0.4064)
			(stroke
				(width 0.1524)
				(type default)
			)
			(layer "F.SilkS")
		)
		(fp_line
			(start -0.7874 -0.4064)
			(end 0.7874 -0.4064)
			(stroke
				(width 0.1524)
				(type default)
			)
			(layer "F.SilkS")
		)
		(fp_line
			(start 0.7874 0.4064)
			(end -0.7874 0.4064)
			(stroke
				(width 0.1524)
				(type default)
			)
			(layer "F.SilkS")
		)
		(fp_line
			(start -0.7874 0.4064)
			(end -0.7874 -0.4064)
			(stroke
				(width 0.1524)
				(type default)
			)
			(layer "F.SilkS")
		)
		(fp_line
			(start -0.12065 -0.305054)
			(end -0.12065 -0.2794)
			(stroke
				(width 0.1)
				(type default)
			)
			(layer "F.Fab")
		)
		(fp_line
			(start -0.67945 -0.305054)
			(end -0.12065 -0.305054)
			(stroke
				(width 0.1)
				(type default)
			)
			(layer "F.Fab")
		)
		(fp_line
			(start 0.67945 -0.3048)
			(end 0.67945 0.3048)
			(stroke
				(width 0.1)
				(type default)
			)
			(layer "F.Fab")
		)
		(fp_line
			(start 0.12065 -0.3048)
			(end 0.67945 -0.3048)
			(stroke
				(width 0.1)
				(type default)
			)
			(layer "F.Fab")
		)
		(fp_line
			(start 0.12065 -0.2794)
			(end 0.12065 -0.3048)
			(stroke
				(width 0.1)
				(type default)
			)
			(layer "F.Fab")
		)
		(fp_line
			(start -0.12065 -0.2794)
			(end 0.12065 -0.2794)
			(stroke
				(width 0.1)
				(type default)
			)
			(layer "F.Fab")
		)
		(fp_line
			(start 0.120396 0.2794)
			(end -0.12065 0.2794)
			(stroke
				(width 0.1)
				(type default)
			)
			(layer "F.Fab")
		)
		(fp_line
			(start -0.12065 0.2794)
			(end -0.12065 0.3048)
			(stroke
				(width 0.1)
				(type default)
			)
			(layer "F.Fab")
		)
		(fp_line
			(start 0.67945 0.3048)
			(end 0.120396 0.3048)
			(stroke
				(width 0.1)
				(type default)
			)
			(layer "F.Fab")
		)
		(fp_line
			(start 0.120396 0.3048)
			(end 0.120396 0.2794)
			(stroke
				(width 0.1)
				(type default)
			)
			(layer "F.Fab")
		)
		(fp_line
			(start -0.12065 0.3048)
			(end -0.67945 0.3048)
			(stroke
				(width 0.1)
				(type default)
			)
			(layer "F.Fab")
		)
		(fp_line
			(start -0.67945 0.3048)
			(end -0.67945 -0.305054)
			(stroke
				(width 0.1)
				(type default)
			)
			(layer "F.Fab")
		)
		(pad "1" smd circle
			(at -0.40005 0 90)
			(size 0 0)
			(layers "F.Cu" "F.Mask" "F.Paste")
			(net "HP_LVC3_OCP_V3_2_P12V_PWRGD")
		)
		(pad "2" smd circle
			(at 0.40005 0 90)
			(size 0 0)
			(layers "F.Cu" "F.Mask" "F.Paste")
			(net "P3V3_OCP_EN_2_R")
		)
	)
)
